FILE_TYPE = MACRO_DRAWING;
SET COLOR_WIRE YELLOW;
SET COLOR_PROP MONO;
SET COLOR_DOT WHITE;
SET COLOR_ARC YELLOW;
SET COLOR_BODY GREEN;
SET COLOR_NOTE MONO;
SET PROP_DISPLAY VALUE;
SET PAGE_NUMBER P168;
FORCEADD OFFPAGE..1
(-7525 2750);
FORCEPROP 2 LAST CDS_LIB mstr_standard
J 0
(-7525 2750);
PAINT ORANGE (-7525 2750);
DISPLAY INVISIBLE (-7525 2750);
FORCEPROP 1 LAST OFFPAGE TRUE
J 0
(-7200 2625);
DISPLAY 0.872340 (-7200 2625);
PAINT GREEN (-7200 2625);
DISPLAY INVISIBLE (-7200 2625);
FORCEPROP 1 LAST COMMENT_BODY TRUE
J 0
(-7400 2650);
DISPLAY 0.872340 (-7400 2650);
PAINT GREEN (-7400 2650);
DISPLAY INVISIBLE (-7400 2650);
FORCEPROP 2 LAST PATH I1
J 0
(-7475 2825);
DISPLAY 1.021277 (-7475 2825);
PAINT ORANGE (-7475 2825);
DISPLAY INVISIBLE (-7475 2825);
FORCEPROP 2 LAST $XR0 155 
J 0
(-7777 2750);
DISPLAY 0.638298 (-7777 2750);
PAINT MONO (-7777 2750);
FORCEPROP 2 LAST $XR1 176 
J 0
(-7777 2750);
DISPLAY 0.638298 (-7777 2750);
PAINT MONO (-7777 2750);
FORCEADD RES..2
(-4225 3050);
FORCEPROP 2 LAST ROOM UART_MUX
J 0
(-4175 3225);
DISPLAY 1.021277 (-4175 3225);
PAINT ORANGE (-4175 3225);
DISPLAY INVISIBLE (-4175 3225);
FORCEPROP 1 LAST PATH I11
J 0
(-4175 3225);
DISPLAY 0.978723 (-4175 3225);
PAINT WHITE (-4175 3225);
DISPLAY INVISIBLE (-4175 3225);
FORCEPROP 2 LAST CDS_LOCATION R1L36
J 0
(-4180 3175);
DISPLAY 0.617021 (-4180 3175);
PAINT AQUA (-4180 3175);
DISPLAY INVISIBLE (-4180 3175);
FORCEPROP 2 LAST SEC 1
J 0
(-4175 3275);
DISPLAY 0.680851 (-4175 3275);
PAINT MONO (-4175 3275);
DISPLAY INVISIBLE (-4175 3275);
FORCEPROP 2 LAST BOM_COST DEBUG
J 0
(-4175 3275);
DISPLAY 1.021277 (-4175 3275);
PAINT ORANGE (-4175 3275);
DISPLAY INVISIBLE (-4175 3275);
FORCEPROP 2 LAST CDS_LIB mstr_discrete
J 0
(-4225 3050);
PAINT ORANGE (-4225 3050);
DISPLAY INVISIBLE (-4225 3050);
FORCEPROP 2 LAST SEC_TYPE 0402
J 0
(-4175 3275);
DISPLAY 1.021277 (-4175 3275);
PAINT ORANGE (-4175 3275);
DISPLAY INVISIBLE (-4175 3275);
FORCEPROP 1 LASTPIN (-4225 3150) $PN 1
J 0
(-4220 3112);
DISPLAY 0.617021 (-4220 3112);
PAINT ORANGE (-4220 3112);
FORCEPROP 1 LASTPIN (-4225 2950) $PN 2
J 0
(-4220 2960);
DISPLAY 0.617021 (-4220 2960);
PAINT ORANGE (-4220 2960);
FORCEPROP 1 LAST WATTAGE 1/16W
J 0
(-4185 3025);
DISPLAY 0.617021 (-4185 3025);
PAINT SKYBLUE (-4185 3025);
FORCEPROP 1 LAST MATERIAL CHIP
J 0
(-4185 2975);
DISPLAY 0.617021 (-4185 2975);
PAINT SKYBLUE (-4185 2975);
FORCEPROP 1 LAST PACK_TYPE 0402
J 0
(-4185 2875);
DISPLAY 0.617021 (-4185 2875);
PAINT SKYBLUE (-4185 2875);
FORCEPROP 1 LAST TOLERANCE 1%
J 0
(-4180 3075);
DISPLAY 0.617021 (-4180 3075);
PAINT SKYBLUE (-4180 3075);
FORCEPROP 1 LAST VALUE 1.00K
J 0
(-4180 3125);
DISPLAY 0.617021 (-4180 3125);
PAINT SKYBLUE (-4180 3125);
FORCEPROP 1 LAST PART_NUMBER G21796-026
J 0
(-4185 2925);
DISPLAY 0.617021 (-4185 2925);
PAINT BLUE (-4185 2925);
FORCEPROP 1 LAST LOCATION R1L36
J 0
(-4180 3175);
DISPLAY 0.617021 (-4180 3175);
PAINT AQUA (-4180 3175);
FORCEADD GND..1
(-4225 2525);
FORCEPROP 3 LASTPIN (-4225 2575) SIG_NAME GND\g
J 0
(-4215 2585);
DISPLAY 0.659574 (-4215 2585);
PAINT MONO (-4215 2585);
DISPLAY INVISIBLE (-4215 2585);
FORCEPROP 1 LAST HDL_POWER GND
J 0
(-4225 2675);
DISPLAY 0.872340 (-4225 2675);
PAINT GREEN (-4225 2675);
DISPLAY INVISIBLE (-4225 2675);
FORCEPROP 1 LAST PATH I14
J 0
(-4150 2525);
DISPLAY 0.872340 (-4150 2525);
PAINT AQUA (-4150 2525);
DISPLAY INVISIBLE (-4150 2525);
FORCEPROP 1 LAST BODY_TYPE PLUMBING
J 0
(-4270 2482);
DISPLAY 0.340426 (-4270 2482);
PAINT GREEN (-4270 2482);
DISPLAY INVISIBLE (-4270 2482);
FORCEPROP 2 LAST CDS_LIB mstr_symbols
J 0
(-4225 2525);
PAINT ORANGE (-4225 2525);
DISPLAY INVISIBLE (-4225 2525);
FORCEPROP 1 LAST SIZE 1B
J 0
(-4150 2475);
DISPLAY 0.872340 (-4150 2475);
PAINT AQUA (-4150 2475);
DISPLAY INVISIBLE (-4150 2475);
FORCEPROP 1 LAST VOLTAGE 0.0V
J 0
(-4270 2482);
DISPLAY 0.340426 (-4270 2482);
PAINT SKYBLUE (-4270 2482);
DISPLAY INVISIBLE (-4270 2482);
FORCEADD FET_N_DUAL..5
(-1525 4425);
FORCEPROP 1 LAST PACK_TYPE SMLF
J 0
(-1325 4275);
DISPLAY 0.978723 (-1325 4275);
PAINT SKYBLUE (-1325 4275);
DISPLAY INVISIBLE (-1325 4275);
FORCEPROP 2 LAST BOM_COST DEBUG
J 0
(-1325 4525);
DISPLAY 1.021277 (-1325 4525);
PAINT ORANGE (-1325 4525);
DISPLAY INVISIBLE (-1325 4525);
FORCEPROP 2 LAST CDS_LIB mstr_discrete
J 0
(-1525 4425);
PAINT MONO (-1525 4425);
DISPLAY INVISIBLE (-1525 4425);
FORCEPROP 2 LAST SEC_TYPE SMLF
J 0
(-1325 4525);
DISPLAY 1.021277 (-1325 4525);
PAINT ORANGE (-1325 4525);
DISPLAY INVISIBLE (-1325 4525);
FORCEPROP 2 LAST SEC 2
J 0
(-1325 4525);
DISPLAY 0.680851 (-1325 4525);
PAINT MONO (-1325 4525);
DISPLAY INVISIBLE (-1325 4525);
FORCEPROP 2 LAST CDS_LOCATION Q1L4
J 0
(-1325 4425);
DISPLAY 0.617021 (-1325 4425);
PAINT AQUA (-1325 4425);
DISPLAY INVISIBLE (-1325 4425);
FORCEPROP 1 LAST PATH I18
J 0
(-1325 4475);
DISPLAY 0.978723 (-1325 4475);
PAINT BLUE (-1325 4475);
DISPLAY INVISIBLE (-1325 4475);
FORCEPROP 2 LAST ROOM UART_MUX
J 0
(-1325 4475);
DISPLAY 1.021277 (-1325 4475);
PAINT ORANGE (-1325 4475);
DISPLAY INVISIBLE (-1325 4475);
FORCEPROP 1 LAST LOCATION Q1L4
J 0
(-1325 4425);
DISPLAY 0.617021 (-1325 4425);
PAINT AQUA (-1325 4425);
FORCEPROP 1 LAST PART_NUMBER D24280-001
J 0
(-1325 4225);
DISPLAY 0.617021 (-1325 4225);
PAINT BLUE (-1325 4225);
FORCEPROP 1 LAST VALUE 2N7002DW
J 0
(-1325 4375);
DISPLAY 0.617021 (-1325 4375);
PAINT SKYBLUE (-1325 4375);
FORCEPROP 1 LAST MATERIAL FET
J 0
(-1325 4325);
DISPLAY 0.617021 (-1325 4325);
PAINT SKYBLUE (-1325 4325);
FORCEPROP 1 LASTPIN (-1525 4225) $PN 4
J 2
(-1467 4225);
DISPLAY 0.617021 (-1467 4225);
PAINT WHITE (-1467 4225);
FORCEPROP 1 LASTPIN (-1725 4325) $PN 5
J 2
(-1722 4340);
DISPLAY 0.617021 (-1722 4340);
PAINT WHITE (-1722 4340);
FORCEPROP 1 LASTPIN (-1525 4625) $PN 3
J 2
(-1472 4590);
DISPLAY 0.617021 (-1472 4590);
PAINT WHITE (-1472 4590);
FORCEADD FET_N_DUAL..5
(-3250 3000);
FORCEPROP 2 LAST ROOM UART_MUX
J 0
(-3050 3050);
DISPLAY 1.021277 (-3050 3050);
PAINT ORANGE (-3050 3050);
DISPLAY INVISIBLE (-3050 3050);
FORCEPROP 1 LAST PATH I19
J 0
(-3050 3050);
DISPLAY 0.978723 (-3050 3050);
PAINT BLUE (-3050 3050);
DISPLAY INVISIBLE (-3050 3050);
FORCEPROP 2 LAST CDS_LOCATION Q1L4
J 0
(-3050 3000);
DISPLAY 0.617021 (-3050 3000);
PAINT AQUA (-3050 3000);
DISPLAY INVISIBLE (-3050 3000);
FORCEPROP 2 LAST SEC 1
J 0
(-3050 3100);
DISPLAY 0.680851 (-3050 3100);
PAINT MONO (-3050 3100);
DISPLAY INVISIBLE (-3050 3100);
FORCEPROP 2 LAST SEC_TYPE SMLF
J 0
(-3050 3100);
DISPLAY 1.021277 (-3050 3100);
PAINT ORANGE (-3050 3100);
DISPLAY INVISIBLE (-3050 3100);
FORCEPROP 2 LAST CDS_LIB mstr_discrete
J 0
(-3250 3000);
PAINT MONO (-3250 3000);
DISPLAY INVISIBLE (-3250 3000);
FORCEPROP 2 LAST BOM_COST DEBUG
J 0
(-3050 3100);
DISPLAY 1.021277 (-3050 3100);
PAINT ORANGE (-3050 3100);
DISPLAY INVISIBLE (-3050 3100);
FORCEPROP 1 LAST PACK_TYPE SMLF
J 0
(-3050 2850);
DISPLAY 0.978723 (-3050 2850);
PAINT SKYBLUE (-3050 2850);
DISPLAY INVISIBLE (-3050 2850);
FORCEPROP 1 LASTPIN (-3250 3200) $PN 6
J 2
(-3197 3165);
DISPLAY 0.617021 (-3197 3165);
PAINT WHITE (-3197 3165);
FORCEPROP 1 LASTPIN (-3450 2900) $PN 2
J 2
(-3447 2915);
DISPLAY 0.617021 (-3447 2915);
PAINT WHITE (-3447 2915);
FORCEPROP 1 LASTPIN (-3250 2800) $PN 1
J 2
(-3192 2800);
DISPLAY 0.617021 (-3192 2800);
PAINT WHITE (-3192 2800);
FORCEPROP 1 LAST MATERIAL FET
J 0
(-3050 2900);
DISPLAY 0.617021 (-3050 2900);
PAINT SKYBLUE (-3050 2900);
FORCEPROP 1 LAST VALUE 2N7002DW
J 0
(-3050 2950);
DISPLAY 0.617021 (-3050 2950);
PAINT SKYBLUE (-3050 2950);
FORCEPROP 1 LAST PART_NUMBER D24280-001
J 0
(-3050 2800);
DISPLAY 0.617021 (-3050 2800);
PAINT BLUE (-3050 2800);
FORCEPROP 1 LAST LOCATION Q1L4
J 0
(-3050 3000);
DISPLAY 0.617021 (-3050 3000);
PAINT AQUA (-3050 3000);
FORCEADD DIODE..1
(-6400 2750);
FORCEPROP 2 LAST ROOM UART_MUX
J 0
(-6425 2950);
DISPLAY 1.021277 (-6425 2950);
PAINT ORANGE (-6425 2950);
DISPLAY INVISIBLE (-6425 2950);
FORCEPROP 1 LAST PATH I2
J 0
(-6420 2960);
DISPLAY 0.978723 (-6420 2960);
PAINT PINK (-6420 2960);
DISPLAY INVISIBLE (-6420 2960);
FORCEPROP 2 LAST CDS_LOCATION CR1L1
J 0
(-6427 2906);
DISPLAY 0.617021 (-6427 2906);
PAINT AQUA (-6427 2906);
DISPLAY INVISIBLE (-6427 2906);
FORCEPROP 2 LAST SEC 1
J 0
(-6400 3025);
DISPLAY 0.680851 (-6400 3025);
PAINT MONO (-6400 3025);
DISPLAY INVISIBLE (-6400 3025);
FORCEPROP 2 LAST BOM_COST DEBUG
J 0
(-6425 3000);
DISPLAY 1.021277 (-6425 3000);
PAINT ORANGE (-6425 3000);
DISPLAY INVISIBLE (-6425 3000);
FORCEPROP 2 LAST CDS_LIB mstr_discrete
J 0
(-6400 2750);
PAINT ORANGE (-6400 2750);
DISPLAY INVISIBLE (-6400 2750);
FORCEPROP 2 LAST SEC_TYPE SM
J 0
(-6400 3025);
DISPLAY 1.021277 (-6400 3025);
PAINT ORANGE (-6400 3025);
DISPLAY INVISIBLE (-6400 3025);
FORCEPROP 1 LASTPIN (-6500 2750) $PN 2
J 2
(-6465 2760);
DISPLAY 0.617021 (-6465 2760);
PAINT AQUA (-6465 2760);
FORCEPROP 1 LASTPIN (-6300 2750) $PN 1
J 0
(-6335 2760);
DISPLAY 0.617021 (-6335 2760);
PAINT AQUA (-6335 2760);
FORCEPROP 1 LAST MATERIAL IC
J 0
(-6425 2572);
DISPLAY 0.617021 (-6425 2572);
PAINT SKYBLUE (-6425 2572);
FORCEPROP 1 LAST PACK_TYPE SM
J 0
(-6425 2510);
DISPLAY 0.617021 (-6425 2510);
PAINT SKYBLUE (-6425 2510);
FORCEPROP 1 LAST PART_NUMBER D89194-001
J 0
(-6425 2850);
DISPLAY 0.617021 (-6425 2850);
PAINT BLUE (-6425 2850);
FORCEPROP 1 LAST LOCATION CR1L1
J 0
(-6427 2906);
DISPLAY 0.617021 (-6427 2906);
PAINT AQUA (-6427 2906);
FORCEPROP 1 LAST VALUE 1N4148W
J 0
(-6425 2625);
DISPLAY 0.617021 (-6425 2625);
PAINT SKYBLUE (-6425 2625);
FORCEADD RES..2
(-3250 3425);
FORCEPROP 2 LAST ROOM UART_MUX
J 0
(-3200 3600);
DISPLAY 1.021277 (-3200 3600);
PAINT ORANGE (-3200 3600);
DISPLAY INVISIBLE (-3200 3600);
FORCEPROP 1 LAST PATH I22
J 0
(-3200 3600);
DISPLAY 0.978723 (-3200 3600);
PAINT WHITE (-3200 3600);
DISPLAY INVISIBLE (-3200 3600);
FORCEPROP 2 LAST CDS_LOCATION R1L38
J 0
(-3205 3550);
DISPLAY 0.617021 (-3205 3550);
PAINT AQUA (-3205 3550);
DISPLAY INVISIBLE (-3205 3550);
FORCEPROP 2 LAST SEC 1
J 0
(-3200 3650);
DISPLAY 0.680851 (-3200 3650);
PAINT MONO (-3200 3650);
DISPLAY INVISIBLE (-3200 3650);
FORCEPROP 2 LAST BOM_COST DEBUG
J 0
(-3200 3650);
DISPLAY 1.021277 (-3200 3650);
PAINT ORANGE (-3200 3650);
DISPLAY INVISIBLE (-3200 3650);
FORCEPROP 2 LAST CDS_LIB mstr_discrete
J 0
(-3250 3425);
PAINT ORANGE (-3250 3425);
DISPLAY INVISIBLE (-3250 3425);
FORCEPROP 2 LAST SEC_TYPE 0402
J 0
(-3200 3650);
DISPLAY 1.021277 (-3200 3650);
PAINT ORANGE (-3200 3650);
DISPLAY INVISIBLE (-3200 3650);
FORCEPROP 1 LASTPIN (-3250 3525) $PN 1
J 0
(-3245 3487);
DISPLAY 0.617021 (-3245 3487);
PAINT ORANGE (-3245 3487);
FORCEPROP 1 LASTPIN (-3250 3325) $PN 2
J 0
(-3245 3335);
DISPLAY 0.617021 (-3245 3335);
PAINT ORANGE (-3245 3335);
FORCEPROP 1 LAST WATTAGE 1/16W
J 0
(-3210 3400);
DISPLAY 0.617021 (-3210 3400);
PAINT SKYBLUE (-3210 3400);
FORCEPROP 1 LAST MATERIAL CHIP
J 0
(-3210 3350);
DISPLAY 0.617021 (-3210 3350);
PAINT SKYBLUE (-3210 3350);
FORCEPROP 1 LAST PACK_TYPE 0402
J 0
(-3210 3250);
DISPLAY 0.617021 (-3210 3250);
PAINT SKYBLUE (-3210 3250);
FORCEPROP 1 LAST TOLERANCE 1%
J 0
(-3205 3450);
DISPLAY 0.617021 (-3205 3450);
PAINT SKYBLUE (-3205 3450);
FORCEPROP 1 LAST VALUE 1.00K
J 0
(-3205 3500);
DISPLAY 0.617021 (-3205 3500);
PAINT SKYBLUE (-3205 3500);
FORCEPROP 1 LAST PART_NUMBER G21796-026
J 0
(-3210 3300);
DISPLAY 0.617021 (-3210 3300);
PAINT BLUE (-3210 3300);
FORCEPROP 1 LAST LOCATION R1L38
J 0
(-3205 3550);
DISPLAY 0.617021 (-3205 3550);
PAINT AQUA (-3205 3550);
FORCEADD P3V3_STBY..1
(-3250 3625);
FORCEPROP 3 LASTPIN (-3250 3575) SIG_NAME P3V3_STBY\g
J 0
(-3240 3585);
DISPLAY 0.659574 (-3240 3585);
PAINT MONO (-3240 3585);
DISPLAY INVISIBLE (-3240 3585);
FORCEPROP 1 LAST HDL_POWER P3V3_STBY
J 0
(-3550 3500);
DISPLAY 0.872340 (-3550 3500);
PAINT ORANGE (-3550 3500);
DISPLAY INVISIBLE (-3550 3500);
FORCEPROP 1 LAST PATH I24
J 0
(-3205 3627);
DISPLAY 0.340426 (-3205 3627);
PAINT GREEN (-3205 3627);
DISPLAY INVISIBLE (-3205 3627);
FORCEPROP 1 LAST BODY_TYPE PLUMBING
J 0
(-3295 3582);
DISPLAY 0.340426 (-3295 3582);
PAINT GREEN (-3295 3582);
DISPLAY INVISIBLE (-3295 3582);
FORCEPROP 1 LAST SIZE 1B
J 0
(-3205 3647);
DISPLAY 0.340426 (-3205 3647);
PAINT GREEN (-3205 3647);
DISPLAY INVISIBLE (-3205 3647);
FORCEPROP 2 LAST CDS_LIB mstr_symbols
J 0
(-3250 3625);
PAINT ORANGE (-3250 3625);
DISPLAY INVISIBLE (-3250 3625);
FORCEPROP 1 LAST VOLTAGE 3.3V
J 0
(-3295 3582);
DISPLAY 0.340426 (-3295 3582);
PAINT SKYBLUE (-3295 3582);
DISPLAY INVISIBLE (-3295 3582);
FORCEADD GND..1
(-3250 2675);
FORCEPROP 3 LASTPIN (-3250 2725) SIG_NAME GND\g
J 0
(-3240 2735);
DISPLAY 0.659574 (-3240 2735);
PAINT MONO (-3240 2735);
DISPLAY INVISIBLE (-3240 2735);
FORCEPROP 1 LAST HDL_POWER GND
J 0
(-3250 2825);
DISPLAY 0.872340 (-3250 2825);
PAINT GREEN (-3250 2825);
DISPLAY INVISIBLE (-3250 2825);
FORCEPROP 1 LAST PATH I26
J 0
(-3175 2675);
DISPLAY 0.872340 (-3175 2675);
PAINT AQUA (-3175 2675);
DISPLAY INVISIBLE (-3175 2675);
FORCEPROP 1 LAST BODY_TYPE PLUMBING
J 0
(-3295 2632);
DISPLAY 0.340426 (-3295 2632);
PAINT GREEN (-3295 2632);
DISPLAY INVISIBLE (-3295 2632);
FORCEPROP 1 LAST SIZE 1B
J 0
(-3175 2625);
DISPLAY 0.872340 (-3175 2625);
PAINT AQUA (-3175 2625);
DISPLAY INVISIBLE (-3175 2625);
FORCEPROP 2 LAST CDS_LIB mstr_symbols
J 0
(-3250 2675);
PAINT ORANGE (-3250 2675);
DISPLAY INVISIBLE (-3250 2675);
FORCEPROP 1 LAST VOLTAGE 0.0V
J 0
(-3295 2632);
DISPLAY 0.340426 (-3295 2632);
PAINT SKYBLUE (-3295 2632);
DISPLAY INVISIBLE (-3295 2632);
FORCEADD OFFPAGE..2
(-2200 3300);
FORCEPROP 2 LAST PATH I28
J 0
(-2025 3375);
DISPLAY 1.021277 (-2025 3375);
PAINT ORANGE (-2025 3375);
DISPLAY INVISIBLE (-2025 3375);
FORCEPROP 1 LAST COMMENT_BODY TRUE
J 0
(-2245 3205);
DISPLAY 0.872340 (-2245 3205);
PAINT GREEN (-2245 3205);
DISPLAY INVISIBLE (-2245 3205);
FORCEPROP 1 LAST OFFPAGE TRUE
J 0
(-1875 3175);
DISPLAY 0.872340 (-1875 3175);
PAINT GREEN (-1875 3175);
DISPLAY INVISIBLE (-1875 3175);
FORCEPROP 2 LAST CDS_LIB mstr_standard
J 0
(-2200 3300);
PAINT ORANGE (-2200 3300);
DISPLAY INVISIBLE (-2200 3300);
FORCEPROP 2 LAST $XR2 147 
J 0
(-1771 3300);
DISPLAY 0.638298 (-1771 3300);
PAINT MONO (-1771 3300);
FORCEPROP 2 LAST $XR1 120 
J 0
(-1891 3300);
DISPLAY 0.638298 (-1891 3300);
PAINT MONO (-1891 3300);
FORCEPROP 2 LAST $XR0 119 
J 0
(-2011 3300);
DISPLAY 0.638298 (-2011 3300);
PAINT MONO (-2011 3300);
FORCEADD P3V3_STBY..1
(-4225 3250);
FORCEPROP 3 LASTPIN (-4225 3200) SIG_NAME P3V3_STBY\g
J 0
(-4215 3210);
DISPLAY 0.659574 (-4215 3210);
PAINT MONO (-4215 3210);
DISPLAY INVISIBLE (-4215 3210);
FORCEPROP 1 LAST HDL_POWER P3V3_STBY
J 0
(-4525 3125);
DISPLAY 0.872340 (-4525 3125);
PAINT ORANGE (-4525 3125);
DISPLAY INVISIBLE (-4525 3125);
FORCEPROP 1 LAST PATH I29
J 0
(-4180 3252);
DISPLAY 0.340426 (-4180 3252);
PAINT GREEN (-4180 3252);
DISPLAY INVISIBLE (-4180 3252);
FORCEPROP 1 LAST BODY_TYPE PLUMBING
J 0
(-4270 3207);
DISPLAY 0.340426 (-4270 3207);
PAINT GREEN (-4270 3207);
DISPLAY INVISIBLE (-4270 3207);
FORCEPROP 1 LAST SIZE 1B
J 0
(-4180 3272);
DISPLAY 0.340426 (-4180 3272);
PAINT GREEN (-4180 3272);
DISPLAY INVISIBLE (-4180 3272);
FORCEPROP 2 LAST CDS_LIB mstr_symbols
J 0
(-4225 3250);
PAINT ORANGE (-4225 3250);
DISPLAY INVISIBLE (-4225 3250);
FORCEPROP 1 LAST VOLTAGE 3.3V
J 0
(-4270 3207);
DISPLAY 0.340426 (-4270 3207);
PAINT SKYBLUE (-4270 3207);
DISPLAY INVISIBLE (-4270 3207);
FORCEADD DIODE..1
(-5850 2750);
FORCEPROP 2 LAST ROOM UART_MUX
J 0
(-5875 2950);
DISPLAY 1.021277 (-5875 2950);
PAINT ORANGE (-5875 2950);
DISPLAY INVISIBLE (-5875 2950);
FORCEPROP 1 LAST PATH I3
J 0
(-5870 2960);
DISPLAY 0.978723 (-5870 2960);
PAINT PINK (-5870 2960);
DISPLAY INVISIBLE (-5870 2960);
FORCEPROP 2 LAST CDS_LOCATION CR1L2
J 0
(-5877 2906);
DISPLAY 0.617021 (-5877 2906);
PAINT AQUA (-5877 2906);
DISPLAY INVISIBLE (-5877 2906);
FORCEPROP 2 LAST SEC 1
J 0
(-5850 3025);
DISPLAY 0.680851 (-5850 3025);
PAINT MONO (-5850 3025);
DISPLAY INVISIBLE (-5850 3025);
FORCEPROP 2 LAST BOM_COST DEBUG
J 0
(-5875 3000);
DISPLAY 1.021277 (-5875 3000);
PAINT ORANGE (-5875 3000);
DISPLAY INVISIBLE (-5875 3000);
FORCEPROP 2 LAST CDS_LIB mstr_discrete
J 0
(-5850 2750);
PAINT ORANGE (-5850 2750);
DISPLAY INVISIBLE (-5850 2750);
FORCEPROP 2 LAST SEC_TYPE SM
J 0
(-5850 3025);
DISPLAY 1.021277 (-5850 3025);
PAINT ORANGE (-5850 3025);
DISPLAY INVISIBLE (-5850 3025);
FORCEPROP 1 LASTPIN (-5950 2750) $PN 2
J 2
(-5915 2760);
DISPLAY 0.617021 (-5915 2760);
PAINT AQUA (-5915 2760);
FORCEPROP 1 LAST MATERIAL IC
J 0
(-5875 2572);
DISPLAY 0.617021 (-5875 2572);
PAINT SKYBLUE (-5875 2572);
FORCEPROP 1 LAST LOCATION CR1L2
J 0
(-5877 2906);
DISPLAY 0.617021 (-5877 2906);
PAINT AQUA (-5877 2906);
FORCEPROP 1 LAST VALUE 1N4148W
J 0
(-5875 2625);
DISPLAY 0.617021 (-5875 2625);
PAINT SKYBLUE (-5875 2625);
FORCEPROP 1 LAST PACK_TYPE SM
J 0
(-5875 2510);
DISPLAY 0.617021 (-5875 2510);
PAINT SKYBLUE (-5875 2510);
FORCEPROP 1 LAST PART_NUMBER D89194-001
J 0
(-5875 2850);
DISPLAY 0.617021 (-5875 2850);
PAINT BLUE (-5875 2850);
FORCEPROP 1 LASTPIN (-5750 2750) $PN 1
J 0
(-5785 2760);
DISPLAY 0.617021 (-5785 2760);
PAINT AQUA (-5785 2760);
FORCEADD OFFPAGE..2
(-3125 1800);
FORCEPROP 2 LAST PATH I31
J 0
(-2675 1850);
DISPLAY 1.021277 (-2675 1850);
PAINT ORANGE (-2675 1850);
DISPLAY INVISIBLE (-2675 1850);
FORCEPROP 2 LAST CDS_LIB mstr_standard
J 0
(-3125 1800);
PAINT ORANGE (-3125 1800);
DISPLAY INVISIBLE (-3125 1800);
FORCEPROP 1 LAST OFFPAGE TRUE
J 0
(-2800 1675);
DISPLAY 0.872340 (-2800 1675);
PAINT GREEN (-2800 1675);
DISPLAY INVISIBLE (-2800 1675);
FORCEPROP 1 LAST COMMENT_BODY TRUE
J 0
(-3170 1705);
DISPLAY 0.872340 (-3170 1705);
PAINT GREEN (-3170 1705);
DISPLAY INVISIBLE (-3170 1705);
FORCEPROP 2 LAST $XR1 144 
J 0
(-2816 1800);
DISPLAY 0.638298 (-2816 1800);
PAINT MONO (-2816 1800);
FORCEPROP 2 LAST $XR0 120 
J 0
(-2936 1800);
DISPLAY 0.638298 (-2936 1800);
PAINT MONO (-2936 1800);
FORCEPROP 2 LAST $XR2 190 
J 0
(-2696 1800);
DISPLAY 0.638298 (-2696 1800);
PAINT MONO (-2696 1800);
FORCEADD GND..1
(-5250 1575);
FORCEPROP 3 LASTPIN (-5250 1625) SIG_NAME GND\g
J 0
(-5240 1635);
DISPLAY 0.659574 (-5240 1635);
PAINT MONO (-5240 1635);
DISPLAY INVISIBLE (-5240 1635);
FORCEPROP 2 LAST CDS_LIB mstr_symbols
J 0
(-5250 1575);
PAINT MONO (-5250 1575);
DISPLAY INVISIBLE (-5250 1575);
FORCEPROP 1 LAST HDL_POWER GND
J 0
(-5250 1725);
DISPLAY 0.872340 (-5250 1725);
PAINT GREEN (-5250 1725);
DISPLAY INVISIBLE (-5250 1725);
FORCEPROP 1 LAST SIZE 1B
J 0
(-5175 1525);
DISPLAY 0.872340 (-5175 1525);
PAINT AQUA (-5175 1525);
DISPLAY INVISIBLE (-5175 1525);
FORCEPROP 1 LAST BODY_TYPE PLUMBING
J 0
(-5295 1532);
DISPLAY 0.340426 (-5295 1532);
PAINT GREEN (-5295 1532);
DISPLAY INVISIBLE (-5295 1532);
FORCEPROP 1 LAST VOLTAGE 0.0V
J 0
(-5295 1532);
DISPLAY 0.340426 (-5295 1532);
PAINT GREEN (-5295 1532);
DISPLAY INVISIBLE (-5295 1532);
FORCEPROP 1 LAST PATH I32
J 0
(-5175 1575);
DISPLAY 0.872340 (-5175 1575);
PAINT AQUA (-5175 1575);
DISPLAY INVISIBLE (-5175 1575);
FORCEADD RES..2
(-5250 1825);
FORCEPROP 1 LASTPIN (-5250 1925) $PN 1
J 0
(-5245 1887);
DISPLAY 0.787234 (-5245 1887);
PAINT ORANGE (-5245 1887);
DISPLAY INVISIBLE (-5245 1887);
FORCEPROP 1 LASTPIN (-5250 1725) $PN 2
J 0
(-5245 1735);
DISPLAY 0.787234 (-5245 1735);
PAINT ORANGE (-5245 1735);
DISPLAY INVISIBLE (-5245 1735);
FORCEPROP 2 LAST BOM_COST SM_HM
J 0
(-5200 2050);
DISPLAY 1.021277 (-5200 2050);
PAINT ORANGE (-5200 2050);
DISPLAY INVISIBLE (-5200 2050);
FORCEPROP 2 LAST ROOM BMC_VOLT_MONITOR
J 0
(-5200 2000);
DISPLAY 1.021277 (-5200 2000);
PAINT ORANGE (-5200 2000);
DISPLAY INVISIBLE (-5200 2000);
FORCEPROP 2 LAST CDS_LIB mstr_discrete
J 0
(-5250 1825);
PAINT MONO (-5250 1825);
DISPLAY INVISIBLE (-5250 1825);
FORCEPROP 1 LAST PATH I33
J 0
(-5200 2000);
DISPLAY 0.978723 (-5200 2000);
PAINT WHITE (-5200 2000);
DISPLAY INVISIBLE (-5200 2000);
FORCEPROP 1 LAST PART_NUMBER G21796-140
J 0
(-5210 1700);
DISPLAY 0.617021 (-5210 1700);
PAINT BLUE (-5210 1700);
FORCEPROP 1 LAST PACK_TYPE 0402
J 0
(-5210 1650);
DISPLAY 0.617021 (-5210 1650);
PAINT SKYBLUE (-5210 1650);
FORCEPROP 1 LAST MATERIAL CHIP
J 0
(-5210 1750);
DISPLAY 0.617021 (-5210 1750);
PAINT SKYBLUE (-5210 1750);
FORCEPROP 1 LAST TOLERANCE 1%
J 0
(-5205 1850);
DISPLAY 0.617021 (-5205 1850);
PAINT SKYBLUE (-5205 1850);
FORCEPROP 1 LAST VALUE 5.11K
J 0
(-5205 1900);
DISPLAY 0.617021 (-5205 1900);
PAINT SKYBLUE (-5205 1900);
FORCEPROP 1 LAST LOCATION R6W14
J 0
(-5205 1950);
DISPLAY 0.617021 (-5205 1950);
PAINT AQUA (-5205 1950);
FORCEPROP 1 LAST WATTAGE 1/16W
J 0
(-5210 1800);
DISPLAY 0.617021 (-5210 1800);
PAINT SKYBLUE (-5210 1800);
FORCEADD RES..2
(-5250 2175);
FORCEPROP 1 LASTPIN (-5250 2275) $PN 1
J 0
(-5245 2237);
DISPLAY 0.787234 (-5245 2237);
PAINT ORANGE (-5245 2237);
DISPLAY INVISIBLE (-5245 2237);
FORCEPROP 1 LASTPIN (-5250 2075) $PN 2
J 0
(-5245 2085);
DISPLAY 0.787234 (-5245 2085);
PAINT ORANGE (-5245 2085);
DISPLAY INVISIBLE (-5245 2085);
FORCEPROP 2 LAST ROOM PVCCIN_CPU1_VR
J 0
(-5200 2350);
DISPLAY 1.361702 (-5200 2350);
PAINT WHITE (-5200 2350);
DISPLAY INVISIBLE (-5200 2350);
FORCEPROP 2 LAST CDS_LIB mstr_discrete
J 0
(-5250 2175);
PAINT MONO (-5250 2175);
DISPLAY INVISIBLE (-5250 2175);
FORCEPROP 1 LAST PATH I34
J 0
(-5200 2350);
DISPLAY 0.978723 (-5200 2350);
PAINT WHITE (-5200 2350);
DISPLAY INVISIBLE (-5200 2350);
FORCEPROP 1 LAST LOCATION R6W13
J 0
(-5205 2300);
DISPLAY 0.617021 (-5205 2300);
PAINT AQUA (-5205 2300);
FORCEPROP 1 LAST VALUE 15.0K
J 0
(-5205 2250);
DISPLAY 0.617021 (-5205 2250);
PAINT SKYBLUE (-5205 2250);
FORCEPROP 1 LAST TOLERANCE 1%
J 0
(-5205 2200);
DISPLAY 0.617021 (-5205 2200);
PAINT SKYBLUE (-5205 2200);
FORCEPROP 1 LAST PACK_TYPE 0402
J 0
(-5210 2000);
DISPLAY 0.617021 (-5210 2000);
PAINT SKYBLUE (-5210 2000);
FORCEPROP 1 LAST PART_NUMBER G21796-107
J 0
(-5210 2050);
DISPLAY 0.617021 (-5210 2050);
PAINT BLUE (-5210 2050);
FORCEPROP 1 LAST MATERIAL CHIP
J 0
(-5210 2100);
DISPLAY 0.617021 (-5210 2100);
PAINT SKYBLUE (-5210 2100);
FORCEPROP 1 LAST WATTAGE 1/16W
J 0
(-5210 2150);
DISPLAY 0.617021 (-5210 2150);
PAINT SKYBLUE (-5210 2150);
FORCEADD P5V_STBY..1
(-5250 2350);
FORCEPROP 3 LASTPIN (-5250 2300) SIG_NAME P5V_STBY\g
J 0
(-5240 2310);
DISPLAY 0.659574 (-5240 2310);
PAINT MONO (-5240 2310);
DISPLAY INVISIBLE (-5240 2310);
FORCEPROP 1 LAST PATH I35
J 0
(-5205 2352);
DISPLAY 0.340426 (-5205 2352);
PAINT GREEN (-5205 2352);
DISPLAY INVISIBLE (-5205 2352);
FORCEPROP 1 LAST VOLTAGE 5.0V
J 0
(-5295 2307);
DISPLAY 0.340426 (-5295 2307);
PAINT GREEN (-5295 2307);
DISPLAY INVISIBLE (-5295 2307);
FORCEPROP 1 LAST SIZE 1B
J 0
(-5205 2372);
DISPLAY 0.340426 (-5205 2372);
PAINT GREEN (-5205 2372);
DISPLAY INVISIBLE (-5205 2372);
FORCEPROP 1 LAST HDL_POWER P5V_STBY
J 0
(-5550 2225);
DISPLAY 0.872340 (-5550 2225);
PAINT ORANGE (-5550 2225);
DISPLAY INVISIBLE (-5550 2225);
FORCEPROP 1 LAST BODY_TYPE PLUMBING
J 0
(-5295 2307);
DISPLAY 0.340426 (-5295 2307);
PAINT GREEN (-5295 2307);
DISPLAY INVISIBLE (-5295 2307);
FORCEPROP 2 LAST CDS_LIB mstr_symbols
J 0
(-5250 2350);
PAINT MONO (-5250 2350);
DISPLAY INVISIBLE (-5250 2350);
FORCEADD GND..1
(-3950 975);
FORCEPROP 3 LASTPIN (-3950 1025) SIG_NAME GND\g
J 0
(-3940 1035);
DISPLAY 0.659574 (-3940 1035);
PAINT MONO (-3940 1035);
DISPLAY INVISIBLE (-3940 1035);
FORCEPROP 1 LAST HDL_POWER GND
J 0
(-3950 1125);
DISPLAY 0.872340 (-3950 1125);
PAINT GREEN (-3950 1125);
DISPLAY INVISIBLE (-3950 1125);
FORCEPROP 1 LAST BODY_TYPE PLUMBING
J 0
(-3995 932);
DISPLAY 0.340426 (-3995 932);
PAINT GREEN (-3995 932);
DISPLAY INVISIBLE (-3995 932);
FORCEPROP 1 LAST SIZE 1B
J 0
(-3875 925);
DISPLAY 0.872340 (-3875 925);
PAINT AQUA (-3875 925);
DISPLAY INVISIBLE (-3875 925);
FORCEPROP 2 LAST CDS_LIB mstr_symbols
J 0
(-3950 975);
PAINT ORANGE (-3950 975);
DISPLAY INVISIBLE (-3950 975);
FORCEPROP 1 LAST VOLTAGE 0.0V
J 0
(-3995 932);
DISPLAY 0.340426 (-3995 932);
PAINT SKYBLUE (-3995 932);
DISPLAY INVISIBLE (-3995 932);
FORCEPROP 1 LAST PATH I36
J 0
(-3875 975);
DISPLAY 0.872340 (-3875 975);
PAINT AQUA (-3875 975);
DISPLAY INVISIBLE (-3875 975);
FORCEADD NPN..1
R 5
(-5975 1500);
FORCEPROP 2 LAST CDS_LOCATION Q6W3
R 3
J 0
(-5925 1350);
DISPLAY 0.617021 (-5925 1350);
PAINT AQUA (-5925 1350);
DISPLAY INVISIBLE (-5925 1350);
FORCEPROP 2 LAST ROOM UART_MUX
R 3
J 0
(-5875 1350);
DISPLAY 1.021277 (-5875 1350);
PAINT ORANGE (-5875 1350);
DISPLAY INVISIBLE (-5875 1350);
FORCEPROP 2 LAST SEC 1
R 3
J 0
(-5825 1350);
DISPLAY 0.680851 (-5825 1350);
PAINT MONO (-5825 1350);
DISPLAY INVISIBLE (-5825 1350);
FORCEPROP 2 LAST BOM_COST DEBUG
R 3
J 0
(-5825 1350);
DISPLAY 1.021277 (-5825 1350);
PAINT ORANGE (-5825 1350);
DISPLAY INVISIBLE (-5825 1350);
FORCEPROP 2 LAST CDS_LIB mstr_discrete
R 3
J 0
(-5975 1500);
PAINT ORANGE (-5975 1500);
DISPLAY INVISIBLE (-5975 1500);
FORCEPROP 2 LAST SEC_TYPE SM
R 3
J 0
(-5825 1350);
DISPLAY 1.021277 (-5825 1350);
PAINT ORANGE (-5825 1350);
DISPLAY INVISIBLE (-5825 1350);
FORCEPROP 0 LAST CDS_SEC 1
R 3
J 0
(-5875 1350);
PAINT MONO (-5875 1350);
DISPLAY INVISIBLE (-5875 1350);
FORCEPROP 1 LAST PATH I37
R 3
J 0
(-5875 1350);
DISPLAY 0.978723 (-5875 1350);
PAINT BLUE (-5875 1350);
DISPLAY INVISIBLE (-5875 1350);
FORCEPROP 1 LAST PACK_TYPE SM
R 3
J 0
(-6075 1350);
DISPLAY 0.617021 (-6075 1350);
PAINT SKYBLUE (-6075 1350);
FORCEPROP 1 LASTPIN (-6075 1450) $PN 2
R 3
J 0
(-6125 1425);
DISPLAY 0.617021 (-6125 1425);
PAINT GREEN (-6125 1425);
FORCEPROP 1 LASTPIN (-5975 1600) $PN 1
R 3
J 0
(-5950 1655);
DISPLAY 0.617021 (-5950 1655);
PAINT GREEN (-5950 1655);
FORCEPROP 1 LASTPIN (-5875 1450) $PN 3
R 3
J 0
(-5865 1431);
DISPLAY 0.617021 (-5865 1431);
PAINT GREEN (-5865 1431);
FORCEPROP 1 LAST VALUE MMBT3904
R 3
J 0
(-5975 1350);
DISPLAY 0.617021 (-5975 1350);
PAINT SKYBLUE (-5975 1350);
FORCEPROP 1 LAST PART_NUMBER C52245-001
R 3
J 0
(-6125 1350);
DISPLAY 0.617021 (-6125 1350);
PAINT BLUE (-6125 1350);
FORCEPROP 1 LAST MATERIAL IC
R 3
J 0
(-6025 1350);
DISPLAY 0.617021 (-6025 1350);
PAINT SKYBLUE (-6025 1350);
FORCEPROP 1 LAST LOCATION Q6W3
R 3
J 0
(-5925 1350);
DISPLAY 0.617021 (-5925 1350);
PAINT AQUA (-5925 1350);
FORCEADD P3V3_STBY..1
(-3950 2375);
FORCEPROP 3 LASTPIN (-3950 2325) SIG_NAME P3V3_STBY\g
J 0
(-3940 2335);
DISPLAY 0.659574 (-3940 2335);
PAINT MONO (-3940 2335);
DISPLAY INVISIBLE (-3940 2335);
FORCEPROP 1 LAST HDL_POWER P3V3_STBY
J 0
(-4250 2250);
DISPLAY 0.872340 (-4250 2250);
PAINT ORANGE (-4250 2250);
DISPLAY INVISIBLE (-4250 2250);
FORCEPROP 1 LAST BODY_TYPE PLUMBING
J 0
(-3995 2332);
DISPLAY 0.340426 (-3995 2332);
PAINT GREEN (-3995 2332);
DISPLAY INVISIBLE (-3995 2332);
FORCEPROP 1 LAST SIZE 1B
J 0
(-3905 2397);
DISPLAY 0.340426 (-3905 2397);
PAINT GREEN (-3905 2397);
DISPLAY INVISIBLE (-3905 2397);
FORCEPROP 2 LAST CDS_LIB mstr_symbols
J 0
(-3950 2375);
PAINT ORANGE (-3950 2375);
DISPLAY INVISIBLE (-3950 2375);
FORCEPROP 1 LAST VOLTAGE 3.3V
J 0
(-3995 2332);
DISPLAY 0.340426 (-3995 2332);
PAINT SKYBLUE (-3995 2332);
DISPLAY INVISIBLE (-3995 2332);
FORCEPROP 1 LAST PATH I38
J 0
(-3905 2377);
DISPLAY 0.340426 (-3905 2377);
PAINT GREEN (-3905 2377);
DISPLAY INVISIBLE (-3905 2377);
FORCEADD RES..2
(-3950 2000);
FORCEPROP 1 LASTPIN (-3950 2100) $PN 1
J 0
(-3945 2062);
DISPLAY 0.787234 (-3945 2062);
PAINT ORANGE (-3945 2062);
DISPLAY INVISIBLE (-3945 2062);
FORCEPROP 1 LASTPIN (-3950 1900) $PN 2
J 0
(-3945 1910);
DISPLAY 0.787234 (-3945 1910);
PAINT ORANGE (-3945 1910);
DISPLAY INVISIBLE (-3945 1910);
FORCEPROP 2 LAST CDS_LIB mstr_discrete
J 0
(-3950 2000);
PAINT MONO (-3950 2000);
DISPLAY INVISIBLE (-3950 2000);
FORCEPROP 1 LAST PATH I39
J 0
(-3900 2175);
DISPLAY 0.978723 (-3900 2175);
PAINT WHITE (-3900 2175);
DISPLAY INVISIBLE (-3900 2175);
FORCEPROP 2 LAST ROOM HOT_SWAP
J 0
(-3900 2175);
PAINT MONO (-3900 2175);
DISPLAY INVISIBLE (-3900 2175);
FORCEPROP 1 LAST PACK_TYPE 0402
J 0
(-3910 1825);
DISPLAY 0.617021 (-3910 1825);
PAINT SKYBLUE (-3910 1825);
FORCEPROP 1 LAST MATERIAL CHIP
J 0
(-3910 1925);
DISPLAY 0.617021 (-3910 1925);
PAINT SKYBLUE (-3910 1925);
FORCEPROP 1 LAST WATTAGE 1/16W
J 0
(-3910 1975);
DISPLAY 0.617021 (-3910 1975);
PAINT SKYBLUE (-3910 1975);
FORCEPROP 1 LAST VALUE 10.0K
J 0
(-3905 2075);
DISPLAY 0.617021 (-3905 2075);
PAINT SKYBLUE (-3905 2075);
FORCEPROP 1 LAST LOCATION R6W16
J 0
(-3905 2125);
DISPLAY 0.617021 (-3905 2125);
PAINT AQUA (-3905 2125);
FORCEPROP 1 LAST TOLERANCE 1%
J 0
(-3905 2025);
DISPLAY 0.617021 (-3905 2025);
PAINT SKYBLUE (-3905 2025);
FORCEPROP 1 LAST PART_NUMBER G21796-016
J 0
(-3910 1875);
DISPLAY 0.617021 (-3910 1875);
PAINT BLUE (-3910 1875);
FORCEADD DIODE..1
(-5375 2750);
FORCEPROP 2 LAST ROOM UART_MUX
J 0
(-5400 2950);
DISPLAY 1.021277 (-5400 2950);
PAINT ORANGE (-5400 2950);
DISPLAY INVISIBLE (-5400 2950);
FORCEPROP 1 LAST PATH I4
J 0
(-5395 2960);
DISPLAY 0.978723 (-5395 2960);
PAINT PINK (-5395 2960);
DISPLAY INVISIBLE (-5395 2960);
FORCEPROP 2 LAST CDS_LOCATION CR1L3
J 0
(-5402 2906);
DISPLAY 0.617021 (-5402 2906);
PAINT AQUA (-5402 2906);
DISPLAY INVISIBLE (-5402 2906);
FORCEPROP 2 LAST SEC 1
J 0
(-5375 3025);
DISPLAY 0.680851 (-5375 3025);
PAINT MONO (-5375 3025);
DISPLAY INVISIBLE (-5375 3025);
FORCEPROP 2 LAST BOM_COST DEBUG
J 0
(-5400 3000);
DISPLAY 1.021277 (-5400 3000);
PAINT ORANGE (-5400 3000);
DISPLAY INVISIBLE (-5400 3000);
FORCEPROP 2 LAST CDS_LIB mstr_discrete
J 0
(-5375 2750);
PAINT ORANGE (-5375 2750);
DISPLAY INVISIBLE (-5375 2750);
FORCEPROP 2 LAST SEC_TYPE SM
J 0
(-5375 3025);
DISPLAY 1.021277 (-5375 3025);
PAINT ORANGE (-5375 3025);
DISPLAY INVISIBLE (-5375 3025);
FORCEPROP 1 LASTPIN (-5475 2750) $PN 2
J 2
(-5440 2760);
DISPLAY 0.617021 (-5440 2760);
PAINT AQUA (-5440 2760);
FORCEPROP 1 LASTPIN (-5275 2750) $PN 1
J 0
(-5310 2760);
DISPLAY 0.617021 (-5310 2760);
PAINT AQUA (-5310 2760);
FORCEPROP 1 LAST MATERIAL IC
J 0
(-5400 2572);
DISPLAY 0.617021 (-5400 2572);
PAINT SKYBLUE (-5400 2572);
FORCEPROP 1 LAST PACK_TYPE SM
J 0
(-5400 2510);
DISPLAY 0.617021 (-5400 2510);
PAINT SKYBLUE (-5400 2510);
FORCEPROP 1 LAST LOCATION CR1L3
J 0
(-5402 2906);
DISPLAY 0.617021 (-5402 2906);
PAINT AQUA (-5402 2906);
FORCEPROP 1 LAST VALUE 1N4148W
J 0
(-5400 2625);
DISPLAY 0.617021 (-5400 2625);
PAINT SKYBLUE (-5400 2625);
FORCEPROP 1 LAST PART_NUMBER D89194-001
J 0
(-5400 2850);
DISPLAY 0.617021 (-5400 2850);
PAINT BLUE (-5400 2850);
FORCEADD RES..2
(-4500 2000);
FORCEPROP 1 LASTPIN (-4500 2100) $PN 1
J 0
(-4495 2062);
DISPLAY 0.787234 (-4495 2062);
PAINT ORANGE (-4495 2062);
DISPLAY INVISIBLE (-4495 2062);
FORCEPROP 1 LASTPIN (-4500 1900) $PN 2
J 0
(-4495 1910);
DISPLAY 0.787234 (-4495 1910);
PAINT ORANGE (-4495 1910);
DISPLAY INVISIBLE (-4495 1910);
FORCEPROP 2 LAST ROOM HOT_SWAP
J 0
(-4450 2175);
PAINT MONO (-4450 2175);
DISPLAY INVISIBLE (-4450 2175);
FORCEPROP 1 LAST PATH I40
J 0
(-4450 2175);
DISPLAY 0.978723 (-4450 2175);
PAINT WHITE (-4450 2175);
DISPLAY INVISIBLE (-4450 2175);
FORCEPROP 2 LAST CDS_LIB mstr_discrete
J 0
(-4500 2000);
PAINT MONO (-4500 2000);
DISPLAY INVISIBLE (-4500 2000);
FORCEPROP 1 LAST LOCATION R6W15
J 0
(-4455 2125);
DISPLAY 0.617021 (-4455 2125);
PAINT AQUA (-4455 2125);
FORCEPROP 1 LAST WATTAGE 1/16W
J 0
(-4460 1975);
DISPLAY 0.617021 (-4460 1975);
PAINT SKYBLUE (-4460 1975);
FORCEPROP 1 LAST PART_NUMBER G21796-016
J 0
(-4460 1875);
DISPLAY 0.617021 (-4460 1875);
PAINT BLUE (-4460 1875);
FORCEPROP 1 LAST PACK_TYPE 0402
J 0
(-4460 1825);
DISPLAY 0.617021 (-4460 1825);
PAINT SKYBLUE (-4460 1825);
FORCEPROP 1 LAST MATERIAL CHIP
J 0
(-4460 1925);
DISPLAY 0.617021 (-4460 1925);
PAINT SKYBLUE (-4460 1925);
FORCEPROP 1 LAST TOLERANCE 1%
J 0
(-4455 2025);
DISPLAY 0.617021 (-4455 2025);
PAINT SKYBLUE (-4455 2025);
FORCEPROP 1 LAST VALUE 10.0K
J 0
(-4455 2075);
DISPLAY 0.617021 (-4455 2075);
PAINT SKYBLUE (-4455 2075);
FORCEADD FET_N..8
(-3950 1550);
FORCEPROP 1 LAST PACK_TYPE SOT23
J 0
(-3750 1400);
DISPLAY 0.978723 (-3750 1400);
PAINT SKYBLUE (-3750 1400);
DISPLAY INVISIBLE (-3750 1400);
FORCEPROP 2 LAST ROOM V_SUPER
J 0
(-3750 1600);
DISPLAY 1.021277 (-3750 1600);
PAINT ORANGE (-3750 1600);
DISPLAY INVISIBLE (-3750 1600);
FORCEPROP 1 LAST MATERIAL FET
J 0
(-3750 1450);
DISPLAY 0.617021 (-3750 1450);
PAINT SKYBLUE (-3750 1450);
FORCEPROP 1 LAST VALUE 2N7002
J 0
(-3750 1500);
DISPLAY 0.617021 (-3750 1500);
PAINT SKYBLUE (-3750 1500);
FORCEPROP 1 LAST PART_NUMBER C79254-001
J 0
(-3750 1350);
DISPLAY 0.617021 (-3750 1350);
PAINT BLUE (-3750 1350);
FORCEPROP 1 LASTPIN (-4150 1450) $PN ?
J 2
(-4147 1465);
DISPLAY 0.872340 (-4147 1465);
PAINT WHITE (-4147 1465);
DISPLAY INVISIBLE (-4147 1465);
FORCEPROP 1 LASTPIN (-3950 1750) $PN ?
J 2
(-3897 1715);
DISPLAY 0.872340 (-3897 1715);
PAINT WHITE (-3897 1715);
DISPLAY INVISIBLE (-3897 1715);
FORCEPROP 1 LASTPIN (-3950 1350) $PN ?
J 2
(-3892 1350);
DISPLAY 0.872340 (-3892 1350);
PAINT WHITE (-3892 1350);
DISPLAY INVISIBLE (-3892 1350);
FORCEPROP 1 LAST PATH I41
J 0
(-3750 1600);
DISPLAY 0.978723 (-3750 1600);
PAINT BLUE (-3750 1600);
DISPLAY INVISIBLE (-3750 1600);
FORCEPROP 2 LAST CDS_LIB mstr_discrete
J 0
(-3950 1550);
DISPLAY INVISIBLE (-3950 1550);
FORCEPROP 1 LAST LOCATION Q6W2
J 0
(-3750 1550);
DISPLAY 0.617021 (-3750 1550);
PAINT AQUA (-3750 1550);
FORCEADD DIODE..1
(-4875 2750);
FORCEPROP 2 LAST ROOM UART_MUX
J 0
(-4900 2950);
DISPLAY 1.021277 (-4900 2950);
PAINT ORANGE (-4900 2950);
DISPLAY INVISIBLE (-4900 2950);
FORCEPROP 1 LAST PATH I5
J 0
(-4895 2960);
DISPLAY 0.978723 (-4895 2960);
PAINT PINK (-4895 2960);
DISPLAY INVISIBLE (-4895 2960);
FORCEPROP 2 LAST CDS_LOCATION CR1L4
J 0
(-4902 2906);
DISPLAY 0.617021 (-4902 2906);
PAINT AQUA (-4902 2906);
DISPLAY INVISIBLE (-4902 2906);
FORCEPROP 2 LAST SEC 1
J 0
(-4875 3025);
DISPLAY 0.680851 (-4875 3025);
PAINT MONO (-4875 3025);
DISPLAY INVISIBLE (-4875 3025);
FORCEPROP 2 LAST BOM_COST DEBUG
J 0
(-4900 3000);
DISPLAY 1.021277 (-4900 3000);
PAINT ORANGE (-4900 3000);
DISPLAY INVISIBLE (-4900 3000);
FORCEPROP 2 LAST CDS_LIB mstr_discrete
J 0
(-4875 2750);
PAINT ORANGE (-4875 2750);
DISPLAY INVISIBLE (-4875 2750);
FORCEPROP 2 LAST SEC_TYPE SM
J 0
(-4875 3025);
DISPLAY 1.021277 (-4875 3025);
PAINT ORANGE (-4875 3025);
DISPLAY INVISIBLE (-4875 3025);
FORCEPROP 1 LAST VALUE 1N4148W
J 0
(-4900 2625);
DISPLAY 0.617021 (-4900 2625);
PAINT SKYBLUE (-4900 2625);
FORCEPROP 1 LASTPIN (-4975 2750) $PN 2
J 2
(-4940 2760);
DISPLAY 0.617021 (-4940 2760);
PAINT AQUA (-4940 2760);
FORCEPROP 1 LASTPIN (-4775 2750) $PN 1
J 0
(-4810 2760);
DISPLAY 0.617021 (-4810 2760);
PAINT AQUA (-4810 2760);
FORCEPROP 1 LAST MATERIAL IC
J 0
(-4900 2572);
DISPLAY 0.617021 (-4900 2572);
PAINT SKYBLUE (-4900 2572);
FORCEPROP 1 LAST PACK_TYPE SM
J 0
(-4900 2510);
DISPLAY 0.617021 (-4900 2510);
PAINT SKYBLUE (-4900 2510);
FORCEPROP 1 LAST LOCATION CR1L4
J 0
(-4902 2906);
DISPLAY 0.617021 (-4902 2906);
PAINT AQUA (-4902 2906);
FORCEPROP 1 LAST PART_NUMBER D89194-001
J 0
(-4900 2850);
DISPLAY 0.617021 (-4900 2850);
PAINT BLUE (-4900 2850);
FORCEADD RES..1
(-6975 2750);
FORCEPROP 2 LAST ROOM UART_MUX
J 0
(-7025 2900);
DISPLAY 1.021277 (-7025 2900);
PAINT ORANGE (-7025 2900);
DISPLAY INVISIBLE (-7025 2900);
FORCEPROP 1 LAST PATH I6
J 0
(-7025 2900);
DISPLAY 0.978723 (-7025 2900);
PAINT WHITE (-7025 2900);
DISPLAY INVISIBLE (-7025 2900);
FORCEPROP 2 LAST CDS_LOCATION R1L6
J 0
(-7025 2800);
DISPLAY 0.617021 (-7025 2800);
PAINT AQUA (-7025 2800);
DISPLAY INVISIBLE (-7025 2800);
FORCEPROP 2 LAST SEC 1
J 0
(-7025 2950);
DISPLAY 0.680851 (-7025 2950);
PAINT MONO (-7025 2950);
DISPLAY INVISIBLE (-7025 2950);
FORCEPROP 2 LAST BOM_COST DEBUG
J 0
(-7025 2950);
DISPLAY 1.021277 (-7025 2950);
PAINT ORANGE (-7025 2950);
DISPLAY INVISIBLE (-7025 2950);
FORCEPROP 2 LAST CDS_LIB mstr_discrete
J 0
(-6975 2750);
PAINT ORANGE (-6975 2750);
DISPLAY INVISIBLE (-6975 2750);
FORCEPROP 2 LAST SEC_TYPE 0402
J 0
(-7025 2950);
DISPLAY 1.021277 (-7025 2950);
PAINT ORANGE (-7025 2950);
DISPLAY INVISIBLE (-7025 2950);
FORCEPROP 1 LASTPIN (-7075 2750) $PN 1
J 0
(-7063 2762);
DISPLAY 0.617021 (-7063 2762);
PAINT ORANGE (-7063 2762);
FORCEPROP 1 LASTPIN (-6875 2750) $PN 2
J 0
(-6913 2762);
DISPLAY 0.617021 (-6913 2762);
PAINT ORANGE (-6913 2762);
FORCEPROP 1 LAST WATTAGE 1/16W
J 2
(-7000 2600);
DISPLAY 0.617021 (-7000 2600);
PAINT SKYBLUE (-7000 2600);
FORCEPROP 1 LAST MATERIAL CHIP
J 0
(-6975 2600);
DISPLAY 0.617021 (-6975 2600);
PAINT SKYBLUE (-6975 2600);
FORCEPROP 1 LAST TOLERANCE 5%
J 0
(-6975 2650);
DISPLAY 0.617021 (-6975 2650);
PAINT SKYBLUE (-6975 2650);
FORCEPROP 1 LAST VALUE 0.0
J 2
(-7000 2650);
DISPLAY 0.617021 (-7000 2650);
PAINT SKYBLUE (-7000 2650);
FORCEPROP 1 LAST PACK_TYPE 0402
J 0
(-7025 2550);
DISPLAY 0.617021 (-7025 2550);
PAINT SKYBLUE (-7025 2550);
FORCEPROP 1 LAST PART_NUMBER G21497-005
J 0
(-7025 2850);
DISPLAY 0.617021 (-7025 2850);
PAINT BLUE (-7025 2850);
FORCEPROP 1 LAST LOCATION R1L6
J 0
(-7025 2800);
DISPLAY 0.617021 (-7025 2800);
PAINT AQUA (-7025 2800);
FORCEADD NPN..1
(-4275 2750);
FORCEPROP 2 LAST ROOM UART_MUX
J 0
(-4125 2850);
DISPLAY 1.021277 (-4125 2850);
PAINT ORANGE (-4125 2850);
DISPLAY INVISIBLE (-4125 2850);
FORCEPROP 1 LAST PATH I8
J 0
(-4125 2850);
DISPLAY 0.978723 (-4125 2850);
PAINT BLUE (-4125 2850);
DISPLAY INVISIBLE (-4125 2850);
FORCEPROP 2 LAST CDS_LOCATION Q1L3
J 0
(-4125 2800);
DISPLAY 0.617021 (-4125 2800);
PAINT AQUA (-4125 2800);
DISPLAY INVISIBLE (-4125 2800);
FORCEPROP 2 LAST SEC 1
J 0
(-4125 2900);
DISPLAY 0.680851 (-4125 2900);
PAINT MONO (-4125 2900);
DISPLAY INVISIBLE (-4125 2900);
FORCEPROP 2 LAST BOM_COST DEBUG
J 0
(-4125 2900);
DISPLAY 1.021277 (-4125 2900);
PAINT ORANGE (-4125 2900);
DISPLAY INVISIBLE (-4125 2900);
FORCEPROP 2 LAST CDS_LIB mstr_discrete
J 0
(-4275 2750);
PAINT ORANGE (-4275 2750);
DISPLAY INVISIBLE (-4275 2750);
FORCEPROP 2 LAST SEC_TYPE SM
J 0
(-4125 2900);
DISPLAY 1.021277 (-4125 2900);
PAINT ORANGE (-4125 2900);
DISPLAY INVISIBLE (-4125 2900);
FORCEPROP 1 LASTPIN (-4375 2750) $PN 1
J 0
(-4430 2775);
DISPLAY 0.617021 (-4430 2775);
PAINT GREEN (-4430 2775);
FORCEPROP 1 LASTPIN (-4225 2850) $PN 3
J 0
(-4206 2860);
DISPLAY 0.617021 (-4206 2860);
PAINT GREEN (-4206 2860);
FORCEPROP 1 LAST MATERIAL IC
J 0
(-4125 2700);
DISPLAY 0.617021 (-4125 2700);
PAINT SKYBLUE (-4125 2700);
FORCEPROP 1 LAST LOCATION Q1L3
J 0
(-4125 2800);
DISPLAY 0.617021 (-4125 2800);
PAINT AQUA (-4125 2800);
FORCEPROP 1 LAST PACK_TYPE SM
J 0
(-4125 2650);
DISPLAY 0.617021 (-4125 2650);
PAINT SKYBLUE (-4125 2650);
FORCEPROP 1 LAST VALUE MMBT3904
J 0
(-4125 2750);
DISPLAY 0.617021 (-4125 2750);
PAINT SKYBLUE (-4125 2750);
FORCEPROP 1 LAST PART_NUMBER C52245-001
J 0
(-4125 2600);
DISPLAY 0.617021 (-4125 2600);
PAINT BLUE (-4125 2600);
FORCEPROP 1 LASTPIN (-4225 2650) $PN 2
J 0
(-4200 2600);
DISPLAY 0.617021 (-4200 2600);
PAINT GREEN (-4200 2600);
FORCEADD INTEL_CORP_BPAGE..1
(0 0);
FORCEPROP 1 LAST CDS_CON_LAST_MODIFIED Tue Dec 01 15:06:59 2015
J 0
(-1425 325);
DISPLAY 1.361702 (-1425 325);
PAINT GREEN (-1425 325);
DISPLAY INVISIBLE (-1425 325);
FORCEPROP 1 LAST CUSTOM_TXT_CDS <CON_LAST_MODIFIED>
J 0
(-1925 350);
PAINT ORANGE (-1925 350);
FORCEPROP 2 LAST CUSTOM_TXT_CDS <XR_PAGE_TITLE>
J 0
(-7890 5250);
DISPLAY 0.638298 (-7890 5250);
PAINT PINK (-7890 5250);
DISPLAY INVISIBLE (-7890 5250);
FORCEPROP 1 LAST CUSTOM_TXT_CDS <CURRENT_DESIGN_SHEET> OF <TOTAL_DESIGN_SHEETS>
J 0
(-500 25);
PAINT ORANGE (-500 25);
FORCEPROP 2 LAST CDS_XR_PAGE_TITLE CR-168 : @BASEBOARD_FAB2_LIB.BASEBOARD_FAB2(SCH_1):PAGE168
J 0
(-7890 5250);
DISPLAY 0.638298 (-7890 5250);
PAINT PINK (-7890 5250);
DISPLAY INVISIBLE (-7890 5250);
FORCEPROP 2 LAST PAGE_BORDER TRUE
J 0
(-7890 5250);
DISPLAY 0.851064 (-7890 5250);
PAINT PINK (-7890 5250);
DISPLAY INVISIBLE (-7890 5250);
FORCEPROP 2 LAST CDS_LIB mstr_symbols
J 0
(0 0);
DISPLAY 1.361702 (0 0);
PAINT ORANGE (0 0);
DISPLAY INVISIBLE (0 0);
FORCEPROP 1 LAST COMMENT_BODY TRUE
J 0
(12 12);
DISPLAY 0.617021 (12 12);
PAINT GREEN (12 12);
DISPLAY INVISIBLE (12 12);
FORCEPROP 1 LAST SCH_ADDRESS3 Santa Clara, CA 95052-8119
J 0
(-3975 25);
DISPLAY 0.617021 (-3975 25);
PAINT GREEN (-3975 25);
FORCEPROP 1 LAST SCH_ADDRESS2 P.O. BOX 58119
J 0
(-3975 75);
DISPLAY 0.617021 (-3975 75);
PAINT GREEN (-3975 75);
FORCEPROP 1 LAST SCH_ADDRESS1 2200 Mission College Blvd.
J 0
(-3975 125);
DISPLAY 0.617021 (-3975 125);
PAINT GREEN (-3975 125);
FORCEPROP 1 LAST SCH_REV 2.420
J 0
(-250 150);
DISPLAY 0.978723 (-250 150);
PAINT YELLOW (-250 150);
FORCEPROP 1 LAST SCH_TITLE UART MUX CONTROL
J 0
(-7950 50);
DISPLAY 1.212766 (-7950 50);
PAINT ORANGE (-7950 50);
FORCEPROP 1 LAST SCH_DEPT BESD
J 1
(-4450 100);
DISPLAY 1.212766 (-4450 100);
PAINT YELLOW (-4450 100);
FORCEPROP 1 LAST SCH_NUMBER H4694802
J 0
(-1300 150);
DISPLAY 1.212766 (-1300 150);
PAINT YELLOW (-1300 150);
WIRE 16 -1 (-4225 2575)(-4225 2650);
WIRE 16 -1 (-3250 3525)(-3250 3575);
WIRE 16 -1 (-3250 2800)(-3250 2725);
WIRE 16 -1 (-4225 3150)(-4225 3200);
WIRE 16 -1 (-5250 1625)(-5250 1725);
WIRE 16 -1 (-5250 2300)(-5250 2275);
WIRE 16 -1 (-3950 1350)(-3950 1025);
WIRE 16 -1 (-3950 2200)(-3950 2325);
WIRE 16 -1 (-4500 2200)(-3950 2200);
WIRE 16 -1 (-3950 2100)(-3950 2200);
WIRE 16 -1 (-4500 2100)(-4500 2200);
WIRE 3 2175 (-6875 2475)(-6875 600);
WIRE 3 2175 (-6875 600)(-2500 600);
WIRE 3 2175 (-6875 2475)(-2500 2475);
WIRE 3 2175 (-2500 2475)(-2500 600);
WIRE 16 -1 (-3950 1900)(-3950 1800);
WIRE 16 -1 (-3950 1800)(-3950 1750);
WIRE 16 -1 (-3175 1800)(-3950 1800);
FORCEPROP 2 LAST SIG_NAME FM_SOL_UART_CH_SEL
J 0
(-3710 1810);
DISPLAY 0.617021 (-3710 1810);
PAINT ORANGE (-3710 1810);
WIRE 16 -1 (-4500 1900)(-4500 1450);
WIRE 16 -1 (-5875 1450)(-4500 1450);
FORCEPROP 2 LAST SIG_NAME FM_UART_SEL_N
J 0
(-5560 1460);
DISPLAY 0.680851 (-5560 1460);
PAINT ORANGE (-5560 1460);
FORCEPROP 2 LASTPROP $XRERR UNIQUE?
J 0
(-5800 1460);
DISPLAY 0.638298 (-5800 1460);
PAINT MONO (-5800 1460);
DISPLAY INVISIBLE (-5800 1460);
WIRE 16 -1 (-4500 1450)(-4150 1450);
WIRE 16 -1 (-5250 1925)(-5250 1975);
WIRE 16 -1 (-5250 2075)(-5250 1975);
WIRE 16 -1 (-5975 1975)(-5975 1600);
WIRE 16 -1 (-5975 1975)(-5250 1975);
FORCEPROP 2 LAST SIG_NAME UART_SELECT_Q
J 0
(-5660 1985);
DISPLAY 0.680851 (-5660 1985);
PAINT ORANGE (-5660 1985);
FORCEPROP 2 LASTPROP $XRERR UNIQUE?
J 0
(-5900 1985);
DISPLAY 0.638298 (-5900 1985);
PAINT MONO (-5900 1985);
DISPLAY INVISIBLE (-5900 1985);
WIRE 16 -1 (-6075 1450)(-7175 1450);
WIRE 16 -1 (-7175 1450)(-7175 2750);
WIRE 16 -1 (-7175 2750)(-7075 2750);
WIRE 16 -1 (-7475 2750)(-7175 2750);
FORCEPROP 2 LAST SIG_NAME FM_UART_SWITCH_N
J 0
(-7485 2760);
DISPLAY 0.617021 (-7485 2760);
PAINT ORANGE (-7485 2760);
WIRE 16 -1 (-5750 2750)(-5475 2750);
FORCEPROP 2 LAST SIG_NAME FM_DB_UART_SEL2_N
J 0
(-5760 2760);
DISPLAY 0.617021 (-5760 2760);
PAINT ORANGE (-5760 2760);
FORCEPROP 2 LASTPROP $XRERR UNIQUE?
J 0
(-6000 2760);
DISPLAY 0.638298 (-6000 2760);
PAINT MONO (-6000 2760);
DISPLAY INVISIBLE (-6000 2760);
WIRE 16 -1 (-6300 2750)(-5950 2750);
FORCEPROP 2 LAST SIG_NAME FM_DB_UART_SEL1_N
J 0
(-6310 2760);
DISPLAY 0.617021 (-6310 2760);
PAINT ORANGE (-6310 2760);
FORCEPROP 2 LASTPROP $XRERR UNIQUE?
J 0
(-6550 2760);
DISPLAY 0.638298 (-6550 2760);
PAINT MONO (-6550 2760);
DISPLAY INVISIBLE (-6550 2760);
WIRE 16 -1 (-4775 2750)(-4375 2750);
FORCEPROP 2 LAST SIG_NAME FM_DB_UART_SEL4_N
J 0
(-4735 2760);
DISPLAY 0.617021 (-4735 2760);
PAINT ORANGE (-4735 2760);
FORCEPROP 2 LASTPROP $XRERR UNIQUE?
J 0
(-4975 2760);
DISPLAY 0.638298 (-4975 2760);
PAINT MONO (-4975 2760);
DISPLAY INVISIBLE (-4975 2760);
WIRE 16 -1 (-4225 2850)(-4225 2900);
WIRE 16 -1 (-3450 2900)(-4225 2900);
FORCEPROP 2 LAST SIG_NAME FM_DB_PRESENT
J 0
(-3960 2910);
DISPLAY 0.617021 (-3960 2910);
PAINT ORANGE (-3960 2910);
FORCEPROP 2 LASTPROP $XRERR UNIQUE?
J 0
(-4200 2910);
DISPLAY 0.638298 (-4200 2910);
PAINT MONO (-4200 2910);
DISPLAY INVISIBLE (-4200 2910);
WIRE 16 -1 (-4225 2950)(-4225 2900);
WIRE 16 -1 (-5275 2750)(-4975 2750);
FORCEPROP 2 LAST SIG_NAME FM_DB_UART_SEL3_N
J 0
(-5260 2760);
DISPLAY 0.617021 (-5260 2760);
PAINT ORANGE (-5260 2760);
FORCEPROP 2 LASTPROP $XRERR UNIQUE?
J 0
(-5500 2760);
DISPLAY 0.638298 (-5500 2760);
PAINT MONO (-5500 2760);
DISPLAY INVISIBLE (-5500 2760);
WIRE 16 -1 (-6875 2750)(-6500 2750);
FORCEPROP 2 LAST SIG_NAME FM_DB_UART_SEL0_N
J 0
(-6860 2760);
DISPLAY 0.617021 (-6860 2760);
PAINT ORANGE (-6860 2760);
FORCEPROP 2 LASTPROP $XRERR UNIQUE?
J 0
(-7100 2760);
DISPLAY 0.638298 (-7100 2760);
PAINT MONO (-7100 2760);
DISPLAY INVISIBLE (-7100 2760);
WIRE 16 -1 (-3250 3200)(-3250 3300);
WIRE 16 -1 (-3250 3300)(-2250 3300);
FORCEPROP 2 LAST SIG_NAME FM_POST_CARD_PRES_BMC_N
J 0
(-2860 3310);
DISPLAY 0.617021 (-2860 3310);
PAINT ORANGE (-2860 3310);
WIRE 16 -1 (-3250 3325)(-3250 3300);
WIRE 16 -1 (-1725 4325)(-1925 4325);
WIRE 16 -1 (-1925 4325)(-1925 4025);
WIRE 16 -1 (-1925 4025)(-1525 4025);
WIRE 16 -1 (-1525 4225)(-1525 4025);
WIRE 16 -1 (-775 4025)(-1525 4025);
FORCEPROP 2 LAST SIG_NAME TP_FET_Q56_4
J 0
(-1385 4035);
DISPLAY 0.617021 (-1385 4035);
PAINT ORANGE (-1385 4035);
FORCEPROP 2 LASTPROP $XRERR UNIQUE?
J 0
(-745 4025);
DISPLAY 0.638298 (-745 4025);
PAINT MONO (-745 4025);
DISPLAY INVISIBLE (-745 4025);
WIRE 16 -1 (-1525 4625)(-1525 4725);
WIRE 16 -1 (-1525 4725)(-800 4725);
FORCEPROP 2 LAST SIG_NAME TP_FET_Q56_3
J 0
(-1385 4735);
DISPLAY 0.617021 (-1385 4735);
PAINT ORANGE (-1385 4735);
FORCEPROP 2 LASTPROP $XRERR UNIQUE?
J 0
(-770 4725);
DISPLAY 0.638298 (-770 4725);
PAINT MONO (-770 4725);
DISPLAY INVISIBLE (-770 4725);
DOT 1 (-3950 2200);
DOT 1 (-3950 1800);
DOT 1 (-4500 1450);
DOT 1 (-7175 2750);
DOT 1 (-4225 2900);
DOT 1 (-3250 3300);
DOT 1 (-1525 4025);
DOT 1 (-5250 1975);
FORCENOTE
TP FAB1 ADD FOR UART SELECT 1117 
(-6600 800) 0;
DISPLAY LEFT (-6600 800);
DISPLAY 1.021277 (-6600 800);
PAINT RED (-6600 800);
QUIT
